# S9S_MB_2U (Grand Teton) — schematic netlist excerpt (pin names and nets, part order shuffled) for the footprints in the layout excerpt that follows; sources: Cadence DE-HDL packaged netlist, KiCad conversion of 03242023_DA0F0TMBIJ0_F0T_Motherboard_J_brd_V01_OCP.brd

PR1332  Q_RES  0 5% CHIP  pkg 0402LF  page 289 : A = PVCCFA_EHV_FIVRA_CPU1_VOS2 ; B = PVCCFA_EHV_FIVRA_CPU1
C2316  Q_CAP  1UF 25V 10% EMPTY  pkg C0402  page 196 : A = P3V3_AUX_USB_HUB_2 ; B = GND

(kicad_pcb
	(version 20260206)
	(generator "pcbnew")
	(generator_version "10.0")
	(general
		(thickness 1.6)
		(legacy_teardrops no)
	)
	(paper "A4")
	(title_block
		(title "03242023_DA0F0TMBIJ0_F0T_Motherboard_J_brd_V01_OCP.brd")
		(comment 1 "Grand Teton / footprints 4717-4718 of 6105")
	)
	(layers
		(0 "F.Cu" signal "TOP")
		(4 "In1.Cu" signal "GND")
		(6 "In2.Cu" signal "IN1")
		(8 "In3.Cu" signal "GND1")
		(10 "In4.Cu" signal "IN2")
		(12 "In5.Cu" signal "GND2")
		(14 "In6.Cu" signal "IN3")
		(16 "In7.Cu" signal "GND3")
		(18 "In8.Cu" signal "VCC")
		(20 "In9.Cu" signal "VCC1")
		(22 "In10.Cu" signal "GND4")
		(24 "In11.Cu" signal "IN4")
		(26 "In12.Cu" signal "GND5")
		(28 "In13.Cu" signal "IN5")
		(30 "In14.Cu" signal "GND6")
		(32 "In15.Cu" signal "IN6")
		(34 "In16.Cu" signal "GND7")
		(2 "B.Cu" signal "BOTTOM")
		(9 "F.Adhes" user "F.Adhesive")
		(11 "B.Adhes" user "B.Adhesive")
		(13 "F.Paste" user "Package Geometry/Pastemask Top")
		(15 "B.Paste" user "Package Geometry/Pastemask Bottom")
		(5 "F.SilkS" user "Ref Des/Silkscreen Top")
		(7 "B.SilkS" user "Ref Des/Silkscreen Bottom")
		(1 "F.Mask" user "Board Geometry/Soldermask Top")
		(3 "B.Mask" user "Board Geometry/Soldermask Bottom")
		(17 "Dwgs.User" user "User.Drawings")
		(19 "Cmts.User" user "User.Comments")
		(21 "Eco1.User" user "User.Eco1")
		(23 "Eco2.User" user "User.Eco2")
		(25 "Edge.Cuts" user "Board Geometry/Outline")
		(27 "Margin" user)
		(31 "F.CrtYd" user "Package Geometry/Place Bound Top")
		(29 "B.CrtYd" user "Package Geometry/Place Bound Bottom")
		(35 "F.Fab" user "Ref Des/Assembly Top")
		(33 "B.Fab" user "Ref Des/Assembly Bottom")
	)
	(footprint ""
		(layer "B.Cu")
		(at 48.506634 -357.92918 -90)
		(property "Reference" "PR1332"
			(at 0 0 90)
			(layer "B.SilkS")
			(hide yes)
			(effects
				(font
					(size 1.27 1.27)
				)
				(justify mirror)
			)
		)
		(property "Value" ""
			(at 0 0 90)
			(layer "B.Fab")
			(effects
				(font
					(size 1.27 1.27)
				)
				(justify mirror)
			)
		)
		(duplicate_pad_numbers_are_jumpers no)
		(fp_line
			(start -0.7874 0.4064)
			(end 0.7874 0.4064)
			(stroke
				(width 0.1524)
				(type default)
			)
			(layer "B.SilkS")
		)
		(fp_line
			(start 0.7874 0.4064)
			(end 0.7874 -0.4064)
			(stroke
				(width 0.1524)
				(type default)
			)
			(layer "B.SilkS")
		)
		(fp_line
			(start -0.7874 -0.4064)
			(end -0.7874 0.4064)
			(stroke
				(width 0.1524)
				(type default)
			)
			(layer "B.SilkS")
		)
		(fp_line
			(start 0.7874 -0.4064)
			(end -0.7874 -0.4064)
			(stroke
				(width 0.1524)
				(type default)
			)
			(layer "B.SilkS")
		)
		(fp_line
			(start -0.67945 0.3048)
			(end -0.120396 0.3048)
			(stroke
				(width 0.1)
				(type default)
			)
			(layer "B.Fab")
		)
		(fp_line
			(start -0.120396 0.3048)
			(end -0.120396 0.2794)
			(stroke
				(width 0.1)
				(type default)
			)
			(layer "B.Fab")
		)
		(fp_line
			(start 0.12065 0.3048)
			(end 0.67945 0.3048)
			(stroke
				(width 0.1)
				(type default)
			)
			(layer "B.Fab")
		)
		(fp_line
			(start 0.67945 0.3048)
			(end 0.67945 -0.305054)
			(stroke
				(width 0.1)
				(type default)
			)
			(layer "B.Fab")
		)
		(fp_line
			(start -0.120396 0.2794)
			(end 0.12065 0.2794)
			(stroke
				(width 0.1)
				(type default)
			)
			(layer "B.Fab")
		)
		(fp_line
			(start 0.12065 0.2794)
			(end 0.12065 0.3048)
			(stroke
				(width 0.1)
				(type default)
			)
			(layer "B.Fab")
		)
		(fp_line
			(start -0.12065 -0.2794)
			(end -0.12065 -0.3048)
			(stroke
				(width 0.1)
				(type default)
			)
			(layer "B.Fab")
		)
		(fp_line
			(start 0.12065 -0.2794)
			(end -0.12065 -0.2794)
			(stroke
				(width 0.1)
				(type default)
			)
			(layer "B.Fab")
		)
		(fp_line
			(start -0.67945 -0.3048)
			(end -0.67945 0.3048)
			(stroke
				(width 0.1)
				(type default)
			)
			(layer "B.Fab")
		)
		(fp_line
			(start -0.12065 -0.3048)
			(end -0.67945 -0.3048)
			(stroke
				(width 0.1)
				(type default)
			)
			(layer "B.Fab")
		)
		(fp_line
			(start 0.12065 -0.305054)
			(end 0.12065 -0.2794)
			(stroke
				(width 0.1)
				(type default)
			)
			(layer "B.Fab")
		)
		(fp_line
			(start 0.67945 -0.305054)
			(end 0.12065 -0.305054)
			(stroke
				(width 0.1)
				(type default)
			)
			(layer "B.Fab")
		)
		(pad "1" smd circle
			(at 0.40005 0 90)
			(size 0 0)
			(layers "B.Cu" "B.Mask" "B.Paste")
			(net "PVCCFA_EHV_FIVRA_CPU1_VOS2")
		)
		(pad "2" smd circle
			(at -0.40005 0 90)
			(size 0 0)
			(layers "B.Cu" "B.Mask" "B.Paste")
			(net "PVCCFA_EHV_FIVRA_CPU1")
		)
	)
	(footprint ""
		(layer "B.Cu")
		(at 159.279082 -37.323268)
		(property "Reference" "C2316"
			(at 0 0 0)
			(layer "B.SilkS")
			(hide yes)
			(effects
				(font
					(size 1.27 1.27)
				)
				(justify mirror)
			)
		)
		(property "Value" ""
			(at 0 0 0)
			(layer "B.Fab")
			(effects
				(font
					(size 1.27 1.27)
				)
				(justify mirror)
			)
		)
		(duplicate_pad_numbers_are_jumpers no)
		(fp_line
			(start -0.7874 -0.4064)
			(end -0.7874 0.4064)
			(stroke
				(width 0.1524)
				(type default)
			)
			(layer "B.SilkS")
		)
		(fp_line
			(start -0.7874 0.4064)
			(end 0.7874 0.4064)
			(stroke
				(width 0.1524)
				(type default)
			)
			(layer "B.SilkS")
		)
		(fp_line
			(start 0.7874 -0.4064)
			(end -0.7874 -0.4064)
			(stroke
				(width 0.1524)
				(type default)
			)
			(layer "B.SilkS")
		)
		(fp_line
			(start 0.7874 0.4064)
			(end 0.7874 -0.4064)
			(stroke
				(width 0.1524)
				(type default)
			)
			(layer "B.SilkS")
		)
		(fp_line
			(start -0.67945 -0.3048)
			(end -0.67945 0.3048)
			(stroke
				(width 0.1)
				(type default)
			)
			(layer "B.Fab")
		)
		(fp_line
			(start -0.67945 0.3048)
			(end -0.120396 0.3048)
			(stroke
				(width 0.1)
				(type default)
			)
			(layer "B.Fab")
		)
		(fp_line
			(start -0.12065 -0.3048)
			(end -0.67945 -0.3048)
			(stroke
				(width 0.1)
				(type default)
			)
			(layer "B.Fab")
		)
		(fp_line
			(start -0.12065 -0.2794)
			(end -0.12065 -0.3048)
			(stroke
				(width 0.1)
				(type default)
			)
			(layer "B.Fab")
		)
		(fp_line
			(start -0.120396 0.2794)
			(end 0.12065 0.2794)
			(stroke
				(width 0.1)
				(type default)
			)
			(layer "B.Fab")
		)
		(fp_line
			(start -0.120396 0.3048)
			(end -0.120396 0.2794)
			(stroke
				(width 0.1)
				(type default)
			)
			(layer "B.Fab")
		)
		(fp_line
			(start 0.12065 -0.305054)
			(end 0.12065 -0.2794)
			(stroke
				(width 0.1)
				(type default)
			)
			(layer "B.Fab")
		)
		(fp_line
			(start 0.12065 -0.2794)
			(end -0.12065 -0.2794)
			(stroke
				(width 0.1)
				(type default)
			)
			(layer "B.Fab")
		)
		(fp_line
			(start 0.12065 0.2794)
			(end 0.12065 0.3048)
			(stroke
				(width 0.1)
				(type default)
			)
			(layer "B.Fab")
		)
		(fp_line
			(start 0.12065 0.3048)
			(end 0.67945 0.3048)
			(stroke
				(width 0.1)
				(type default)
			)
			(layer "B.Fab")
		)
		(fp_line
			(start 0.67945 -0.305054)
			(end 0.12065 -0.305054)
			(stroke
				(width 0.1)
				(type default)
			)
			(layer "B.Fab")
		)
		(fp_line
			(start 0.67945 0.3048)
			(end 0.67945 -0.305054)
			(stroke
				(width 0.1)
				(type default)
			)
			(layer "B.Fab")
		)
		(pad "1" smd circle
			(at 0.40005 0 180)
			(size 0 0)
			(layers "B.Cu" "B.Mask" "B.Paste")
			(net "P3V3_AUX_USB_HUB_2")
		)
		(pad "2" smd circle
			(at -0.40005 0 180)
			(size 0 0)
			(layers "B.Cu" "B.Mask" "B.Paste")
			(net "GND")
		)
	)
)
